(kicad_pcb
	(version 20260206)
	(generator "pcbnew")
	(generator_version "10.0")
	(general
		(thickness 1.6)
		(legacy_teardrops no)
	)
	(paper "A4")
	(title_block
		(title "01162023_DA0F0TEBIF0_F0T_Expander_BD_F_brd_V02_OCP.brd")
		(comment 1 "Grand Teton / footprints 2357-2363 of 9728")
	)
	(layers
		(0 "F.Cu" signal "TOP")
		(4 "In1.Cu" signal "GND")
		(6 "In2.Cu" signal "VCC")
		(8 "In3.Cu" signal "VCC1")
		(10 "In4.Cu" signal "GND1")
		(12 "In5.Cu" signal "IN1")
		(14 "In6.Cu" signal "GND2")
		(16 "In7.Cu" signal "IN2")
		(18 "In8.Cu" signal "GND3")
		(20 "In9.Cu" signal "IN3")
		(22 "In10.Cu" signal "GND4")
		(24 "In11.Cu" signal "IN4")
		(26 "In12.Cu" signal "GND5")
		(28 "In13.Cu" signal "IN5")
		(30 "In14.Cu" signal "GND6")
		(32 "In15.Cu" signal "IN6")
		(34 "In16.Cu" signal "GND7")
		(2 "B.Cu" signal "BOTTOM")
		(9 "F.Adhes" user "F.Adhesive")
		(11 "B.Adhes" user "B.Adhesive")
		(13 "F.Paste" user "Package Geometry/Pastemask Top")
		(15 "B.Paste" user "Package Geometry/Pastemask Bottom")
		(5 "F.SilkS" user "Ref Des/Silkscreen Top")
		(7 "B.SilkS" user "Ref Des/Silkscreen Bottom")
		(1 "F.Mask" user "Board Geometry/Soldermask Top")
		(3 "B.Mask" user "Board Geometry/Soldermask Bottom")
		(17 "Dwgs.User" user "User.Drawings")
		(19 "Cmts.User" user "User.Comments")
		(21 "Eco1.User" user "User.Eco1")
		(23 "Eco2.User" user "User.Eco2")
		(25 "Edge.Cuts" user "Board Geometry/Outline")
		(27 "Margin" user)
		(31 "F.CrtYd" user "Package Geometry/Place Bound Top")
		(29 "B.CrtYd" user "Package Geometry/Place Bound Bottom")
		(35 "F.Fab" user "Ref Des/Assembly Top")
		(33 "B.Fab" user "Ref Des/Assembly Bottom")
	)
	(footprint ""
		(layer "F.Cu")
		(at 459.574646 -306.510436 -90)
		(property "Reference" "PC281"
			(at 0 0 270)
			(layer "F.SilkS")
			(hide yes)
			(effects
				(font
					(size 1.27 1.27)
				)
			)
		)
		(property "Value" ""
			(at 0 0 270)
			(layer "F.Fab")
			(effects
				(font
					(size 1.27 1.27)
				)
			)
		)
		(duplicate_pad_numbers_are_jumpers no)
		(fp_line
			(start -0.7874 0.4064)
			(end -0.7874 -0.4064)
			(stroke
				(width 0.1524)
				(type default)
			)
			(layer "F.SilkS")
		)
		(fp_line
			(start 0.7874 0.4064)
			(end -0.7874 0.4064)
			(stroke
				(width 0.1524)
				(type default)
			)
			(layer "F.SilkS")
		)
		(fp_line
			(start -0.7874 -0.4064)
			(end 0.7874 -0.4064)
			(stroke
				(width 0.1524)
				(type default)
			)
			(layer "F.SilkS")
		)
		(fp_line
			(start 0.7874 -0.4064)
			(end 0.7874 0.4064)
			(stroke
				(width 0.1524)
				(type default)
			)
			(layer "F.SilkS")
		)
		(fp_line
			(start -0.67945 0.3048)
			(end -0.67945 -0.305054)
			(stroke
				(width 0.1)
				(type default)
			)
			(layer "F.Fab")
		)
		(fp_line
			(start -0.12065 0.3048)
			(end -0.67945 0.3048)
			(stroke
				(width 0.1)
				(type default)
			)
			(layer "F.Fab")
		)
		(fp_line
			(start 0.120396 0.3048)
			(end 0.120396 0.2794)
			(stroke
				(width 0.1)
				(type default)
			)
			(layer "F.Fab")
		)
		(fp_line
			(start 0.67945 0.3048)
			(end 0.120396 0.3048)
			(stroke
				(width 0.1)
				(type default)
			)
			(layer "F.Fab")
		)
		(fp_line
			(start -0.12065 0.2794)
			(end -0.12065 0.3048)
			(stroke
				(width 0.1)
				(type default)
			)
			(layer "F.Fab")
		)
		(fp_line
			(start 0.120396 0.2794)
			(end -0.12065 0.2794)
			(stroke
				(width 0.1)
				(type default)
			)
			(layer "F.Fab")
		)
		(fp_line
			(start -0.12065 -0.2794)
			(end 0.12065 -0.2794)
			(stroke
				(width 0.1)
				(type default)
			)
			(layer "F.Fab")
		)
		(fp_line
			(start 0.12065 -0.2794)
			(end 0.12065 -0.3048)
			(stroke
				(width 0.1)
				(type default)
			)
			(layer "F.Fab")
		)
		(fp_line
			(start 0.12065 -0.3048)
			(end 0.67945 -0.3048)
			(stroke
				(width 0.1)
				(type default)
			)
			(layer "F.Fab")
		)
		(fp_line
			(start 0.67945 -0.3048)
			(end 0.67945 0.3048)
			(stroke
				(width 0.1)
				(type default)
			)
			(layer "F.Fab")
		)
		(fp_line
			(start -0.67945 -0.305054)
			(end -0.12065 -0.305054)
			(stroke
				(width 0.1)
				(type default)
			)
			(layer "F.Fab")
		)
		(fp_line
			(start -0.12065 -0.305054)
			(end -0.12065 -0.2794)
			(stroke
				(width 0.1)
				(type default)
			)
			(layer "F.Fab")
		)
		(pad "1" smd circle
			(at -0.40005 0 270)
			(size 0 0)
			(layers "F.Cu" "F.Mask" "F.Paste")
			(net "P1V25_PEX3_REF")
		)
		(pad "2" smd circle
			(at 0.40005 0 270)
			(size 0 0)
			(layers "F.Cu" "F.Mask" "F.Paste")
			(net "GND")
		)
	)
	(footprint ""
		(layer "F.Cu")
		(at 251.996194 -47.20082 90)
		(property "Reference" "C322"
			(at 0 0 90)
			(layer "F.SilkS")
			(hide yes)
			(effects
				(font
					(size 1.27 1.27)
				)
			)
		)
		(property "Value" ""
			(at 0 0 90)
			(layer "F.Fab")
			(effects
				(font
					(size 1.27 1.27)
				)
			)
		)
		(duplicate_pad_numbers_are_jumpers no)
		(fp_line
			(start 0.7874 -0.4064)
			(end 0.7874 0.4064)
			(stroke
				(width 0.1524)
				(type default)
			)
			(layer "F.SilkS")
		)
		(fp_line
			(start -0.7874 -0.4064)
			(end 0.7874 -0.4064)
			(stroke
				(width 0.1524)
				(type default)
			)
			(layer "F.SilkS")
		)
		(fp_line
			(start 0.7874 0.4064)
			(end -0.7874 0.4064)
			(stroke
				(width 0.1524)
				(type default)
			)
			(layer "F.SilkS")
		)
		(fp_line
			(start -0.7874 0.4064)
			(end -0.7874 -0.4064)
			(stroke
				(width 0.1524)
				(type default)
			)
			(layer "F.SilkS")
		)
		(fp_line
			(start -0.12065 -0.305054)
			(end -0.12065 -0.2794)
			(stroke
				(width 0.1)
				(type default)
			)
			(layer "F.Fab")
		)
		(fp_line
			(start -0.67945 -0.305054)
			(end -0.12065 -0.305054)
			(stroke
				(width 0.1)
				(type default)
			)
			(layer "F.Fab")
		)
		(fp_line
			(start 0.67945 -0.3048)
			(end 0.67945 0.3048)
			(stroke
				(width 0.1)
				(type default)
			)
			(layer "F.Fab")
		)
		(fp_line
			(start 0.12065 -0.3048)
			(end 0.67945 -0.3048)
			(stroke
				(width 0.1)
				(type default)
			)
			(layer "F.Fab")
		)
		(fp_line
			(start 0.12065 -0.2794)
			(end 0.12065 -0.3048)
			(stroke
				(width 0.1)
				(type default)
			)
			(layer "F.Fab")
		)
		(fp_line
			(start -0.12065 -0.2794)
			(end 0.12065 -0.2794)
			(stroke
				(width 0.1)
				(type default)
			)
			(layer "F.Fab")
		)
		(fp_line
			(start 0.120396 0.2794)
			(end -0.12065 0.2794)
			(stroke
				(width 0.1)
				(type default)
			)
			(layer "F.Fab")
		)
		(fp_line
			(start -0.12065 0.2794)
			(end -0.12065 0.3048)
			(stroke
				(width 0.1)
				(type default)
			)
			(layer "F.Fab")
		)
		(fp_line
			(start 0.67945 0.3048)
			(end 0.120396 0.3048)
			(stroke
				(width 0.1)
				(type default)
			)
			(layer "F.Fab")
		)
		(fp_line
			(start 0.120396 0.3048)
			(end 0.120396 0.2794)
			(stroke
				(width 0.1)
				(type default)
			)
			(layer "F.Fab")
		)
		(fp_line
			(start -0.12065 0.3048)
			(end -0.67945 0.3048)
			(stroke
				(width 0.1)
				(type default)
			)
			(layer "F.Fab")
		)
		(fp_line
			(start -0.67945 0.3048)
			(end -0.67945 -0.305054)
			(stroke
				(width 0.1)
				(type default)
			)
			(layer "F.Fab")
		)
		(pad "1" smd circle
			(at -0.40005 0 90)
			(size 0 0)
			(layers "F.Cu" "F.Mask" "F.Paste")
			(net "P12V_SSD8_R")
		)
		(pad "2" smd circle
			(at 0.40005 0 90)
			(size 0 0)
			(layers "F.Cu" "F.Mask" "F.Paste")
			(net "GND")
		)
	)
	(footprint ""
		(layer "F.Cu")
		(at 206.623158 -79.595472)
		(property "Reference" "R4307"
			(at 0 0 0)
			(layer "F.SilkS")
			(hide yes)
			(effects
				(font
					(size 1.27 1.27)
				)
			)
		)
		(property "Value" ""
			(at 0 0 0)
			(layer "F.Fab")
			(effects
				(font
					(size 1.27 1.27)
				)
			)
		)
		(duplicate_pad_numbers_are_jumpers no)
		(fp_line
			(start -0.7874 -0.4064)
			(end 0.7874 -0.4064)
			(stroke
				(width 0.1524)
				(type default)
			)
			(layer "F.SilkS")
		)
		(fp_line
			(start -0.7874 0.4064)
			(end -0.7874 -0.4064)
			(stroke
				(width 0.1524)
				(type default)
			)
			(layer "F.SilkS")
		)
		(fp_line
			(start 0.7874 -0.4064)
			(end 0.7874 0.4064)
			(stroke
				(width 0.1524)
				(type default)
			)
			(layer "F.SilkS")
		)
		(fp_line
			(start 0.7874 0.4064)
			(end -0.7874 0.4064)
			(stroke
				(width 0.1524)
				(type default)
			)
			(layer "F.SilkS")
		)
		(fp_line
			(start -0.67945 -0.305054)
			(end -0.12065 -0.305054)
			(stroke
				(width 0.1)
				(type default)
			)
			(layer "F.Fab")
		)
		(fp_line
			(start -0.67945 0.3048)
			(end -0.67945 -0.305054)
			(stroke
				(width 0.1)
				(type default)
			)
			(layer "F.Fab")
		)
		(fp_line
			(start -0.12065 -0.305054)
			(end -0.12065 -0.2794)
			(stroke
				(width 0.1)
				(type default)
			)
			(layer "F.Fab")
		)
		(fp_line
			(start -0.12065 -0.2794)
			(end 0.12065 -0.2794)
			(stroke
				(width 0.1)
				(type default)
			)
			(layer "F.Fab")
		)
		(fp_line
			(start -0.12065 0.2794)
			(end -0.12065 0.3048)
			(stroke
				(width 0.1)
				(type default)
			)
			(layer "F.Fab")
		)
		(fp_line
			(start -0.12065 0.3048)
			(end -0.67945 0.3048)
			(stroke
				(width 0.1)
				(type default)
			)
			(layer "F.Fab")
		)
		(fp_line
			(start 0.120396 0.2794)
			(end -0.12065 0.2794)
			(stroke
				(width 0.1)
				(type default)
			)
			(layer "F.Fab")
		)
		(fp_line
			(start 0.120396 0.3048)
			(end 0.120396 0.2794)
			(stroke
				(width 0.1)
				(type default)
			)
			(layer "F.Fab")
		)
		(fp_line
			(start 0.12065 -0.3048)
			(end 0.67945 -0.3048)
			(stroke
				(width 0.1)
				(type default)
			)
			(layer "F.Fab")
		)
		(fp_line
			(start 0.12065 -0.2794)
			(end 0.12065 -0.3048)
			(stroke
				(width 0.1)
				(type default)
			)
			(layer "F.Fab")
		)
		(fp_line
			(start 0.67945 -0.3048)
			(end 0.67945 0.3048)
			(stroke
				(width 0.1)
				(type default)
			)
			(layer "F.Fab")
		)
		(fp_line
			(start 0.67945 0.3048)
			(end 0.120396 0.3048)
			(stroke
				(width 0.1)
				(type default)
			)
			(layer "F.Fab")
		)
		(pad "1" smd circle
			(at -0.40005 0)
			(size 0 0)
			(layers "F.Cu" "F.Mask" "F.Paste")
			(net "SSD5_LED_R")
		)
		(pad "2" smd circle
			(at 0.40005 0)
			(size 0 0)
			(layers "F.Cu" "F.Mask" "F.Paste")
			(net "SSD5_LED")
		)
	)
	(footprint ""
		(layer "F.Cu")
		(at 495.253772 -522.248892 90)
		(property "Reference" "VR_HS0"
			(at -0.3937 -0.588518 90)
			(unlocked yes)
			(layer "F.SilkS")
			(effects
				(font
					(size 0.254 0.127)
					(thickness 0.000001)
				)
				(justify left)
			)
		)
		(property "Value" ""
			(at 0 0 90)
			(layer "F.Fab")
			(effects
				(font
					(size 1.27 1.27)
				)
			)
		)
		(duplicate_pad_numbers_are_jumpers no)
		(pad "1" smd circle
			(at 0 0 90)
			(size 0.762 0.762)
			(layers "F.Cu" "F.Mask" "F.Paste")
			(net "Net_9198")
		)
	)
	(footprint ""
		(layer "F.Cu")
		(at 142.926308 -356.244906 90)
		(property "Reference" "C2243"
			(at 0 0 90)
			(layer "F.SilkS")
			(hide yes)
			(effects
				(font
					(size 1.27 1.27)
				)
			)
		)
		(property "Value" ""
			(at 0 0 90)
			(layer "F.Fab")
			(effects
				(font
					(size 1.27 1.27)
				)
			)
		)
		(duplicate_pad_numbers_are_jumpers no)
		(fp_line
			(start 0.299974 -0.150114)
			(end 0.299974 0.150114)
			(stroke
				(width 0.1)
				(type default)
			)
			(layer "F.Fab")
		)
		(fp_line
			(start -0.299974 -0.150114)
			(end 0.299974 -0.150114)
			(stroke
				(width 0.1)
				(type default)
			)
			(layer "F.Fab")
		)
		(fp_line
			(start 0.299974 0.150114)
			(end -0.299974 0.150114)
			(stroke
				(width 0.1)
				(type default)
			)
			(layer "F.Fab")
		)
		(fp_line
			(start -0.299974 0.150114)
			(end -0.299974 -0.150114)
			(stroke
				(width 0.1)
				(type default)
			)
			(layer "F.Fab")
		)
		(pad "1" smd rect
			(at -0.2667 0 90)
			(size 0.3048 0.381)
			(layers "F.Cu" "F.Mask" "F.Paste")
			(net "P5E_PEX1_STN5_TX_DP<95>")
		)
		(pad "2" smd rect
			(at 0.2667 0 90)
			(size 0.3048 0.381)
			(layers "F.Cu" "F.Mask" "F.Paste")
			(net "P5E_PEX1_STN5_TX_C_DP<95>")
		)
	)
	(footprint ""
		(layer "F.Cu")
		(at 231.807512 -234.728004 -90)
		(property "Reference" "R6193"
			(at 0 0 270)
			(layer "F.SilkS")
			(hide yes)
			(effects
				(font
					(size 1.27 1.27)
				)
			)
		)
		(property "Value" ""
			(at 0 0 270)
			(layer "F.Fab")
			(effects
				(font
					(size 1.27 1.27)
				)
			)
		)
		(duplicate_pad_numbers_are_jumpers no)
		(fp_line
			(start -0.7874 0.4064)
			(end -0.7874 -0.4064)
			(stroke
				(width 0.1524)
				(type default)
			)
			(layer "F.SilkS")
		)
		(fp_line
			(start 0.7874 0.4064)
			(end -0.7874 0.4064)
			(stroke
				(width 0.1524)
				(type default)
			)
			(layer "F.SilkS")
		)
		(fp_line
			(start -0.7874 -0.4064)
			(end 0.7874 -0.4064)
			(stroke
				(width 0.1524)
				(type default)
			)
			(layer "F.SilkS")
		)
		(fp_line
			(start 0.7874 -0.4064)
			(end 0.7874 0.4064)
			(stroke
				(width 0.1524)
				(type default)
			)
			(layer "F.SilkS")
		)
		(fp_line
			(start -0.67945 0.3048)
			(end -0.67945 -0.305054)
			(stroke
				(width 0.1)
				(type default)
			)
			(layer "F.Fab")
		)
		(fp_line
			(start -0.12065 0.3048)
			(end -0.67945 0.3048)
			(stroke
				(width 0.1)
				(type default)
			)
			(layer "F.Fab")
		)
		(fp_line
			(start 0.120396 0.3048)
			(end 0.120396 0.2794)
			(stroke
				(width 0.1)
				(type default)
			)
			(layer "F.Fab")
		)
		(fp_line
			(start 0.67945 0.3048)
			(end 0.120396 0.3048)
			(stroke
				(width 0.1)
				(type default)
			)
			(layer "F.Fab")
		)
		(fp_line
			(start -0.12065 0.2794)
			(end -0.12065 0.3048)
			(stroke
				(width 0.1)
				(type default)
			)
			(layer "F.Fab")
		)
		(fp_line
			(start 0.120396 0.2794)
			(end -0.12065 0.2794)
			(stroke
				(width 0.1)
				(type default)
			)
			(layer "F.Fab")
		)
		(fp_line
			(start -0.12065 -0.2794)
			(end 0.12065 -0.2794)
			(stroke
				(width 0.1)
				(type default)
			)
			(layer "F.Fab")
		)
		(fp_line
			(start 0.12065 -0.2794)
			(end 0.12065 -0.3048)
			(stroke
				(width 0.1)
				(type default)
			)
			(layer "F.Fab")
		)
		(fp_line
			(start 0.12065 -0.3048)
			(end 0.67945 -0.3048)
			(stroke
				(width 0.1)
				(type default)
			)
			(layer "F.Fab")
		)
		(fp_line
			(start 0.67945 -0.3048)
			(end 0.67945 0.3048)
			(stroke
				(width 0.1)
				(type default)
			)
			(layer "F.Fab")
		)
		(fp_line
			(start -0.67945 -0.305054)
			(end -0.12065 -0.305054)
			(stroke
				(width 0.1)
				(type default)
			)
			(layer "F.Fab")
		)
		(fp_line
			(start -0.12065 -0.305054)
			(end -0.12065 -0.2794)
			(stroke
				(width 0.1)
				(type default)
			)
			(layer "F.Fab")
		)
		(pad "1" smd circle
			(at -0.40005 0 270)
			(size 0 0)
			(layers "F.Cu" "F.Mask" "F.Paste")
			(net "GND")
		)
		(pad "2" smd circle
			(at 0.40005 0 270)
			(size 0 0)
			(layers "F.Cu" "F.Mask" "F.Paste")
			(net "SSD11_PWRDIS_BIC_R")
		)
	)
	(footprint ""
		(layer "F.Cu")
		(at 320.852292 -116.416836 180)
		(property "Reference" "PC902"
			(at 0 0 180)
			(layer "F.SilkS")
			(hide yes)
			(effects
				(font
					(size 1.27 1.27)
				)
			)
		)
		(property "Value" ""
			(at 0 0 180)
			(layer "F.Fab")
			(effects
				(font
					(size 1.27 1.27)
				)
			)
		)
		(duplicate_pad_numbers_are_jumpers no)
		(fp_line
			(start 0.7874 0.4064)
			(end -0.7874 0.4064)
			(stroke
				(width 0.1524)
				(type default)
			)
			(layer "F.SilkS")
		)
		(fp_line
			(start 0.7874 -0.4064)
			(end 0.7874 0.4064)
			(stroke
				(width 0.1524)
				(type default)
			)
			(layer "F.SilkS")
		)
		(fp_line
			(start -0.7874 0.4064)
			(end -0.7874 -0.4064)
			(stroke
				(width 0.1524)
				(type default)
			)
			(layer "F.SilkS")
		)
		(fp_line
			(start -0.7874 -0.4064)
			(end 0.7874 -0.4064)
			(stroke
				(width 0.1524)
				(type default)
			)
			(layer "F.SilkS")
		)
		(fp_line
			(start 0.67945 0.3048)
			(end 0.120396 0.3048)
			(stroke
				(width 0.1)
				(type default)
			)
			(layer "F.Fab")
		)
		(fp_line
			(start 0.67945 -0.3048)
			(end 0.67945 0.3048)
			(stroke
				(width 0.1)
				(type default)
			)
			(layer "F.Fab")
		)
		(fp_line
			(start 0.12065 -0.2794)
			(end 0.12065 -0.3048)
			(stroke
				(width 0.1)
				(type default)
			)
			(layer "F.Fab")
		)
		(fp_line
			(start 0.12065 -0.3048)
			(end 0.67945 -0.3048)
			(stroke
				(width 0.1)
				(type default)
			)
			(layer "F.Fab")
		)
		(fp_line
			(start 0.120396 0.3048)
			(end 0.120396 0.2794)
			(stroke
				(width 0.1)
				(type default)
			)
			(layer "F.Fab")
		)
		(fp_line
			(start 0.120396 0.2794)
			(end -0.12065 0.2794)
			(stroke
				(width 0.1)
				(type default)
			)
			(layer "F.Fab")
		)
		(fp_line
			(start -0.12065 0.3048)
			(end -0.67945 0.3048)
			(stroke
				(width 0.1)
				(type default)
			)
			(layer "F.Fab")
		)
		(fp_line
			(start -0.12065 0.2794)
			(end -0.12065 0.3048)
			(stroke
				(width 0.1)
				(type default)
			)
			(layer "F.Fab")
		)
		(fp_line
			(start -0.12065 -0.2794)
			(end 0.12065 -0.2794)
			(stroke
				(width 0.1)
				(type default)
			)
			(layer "F.Fab")
		)
		(fp_line
			(start -0.12065 -0.305054)
			(end -0.12065 -0.2794)
			(stroke
				(width 0.1)
				(type default)
			)
			(layer "F.Fab")
		)
		(fp_line
			(start -0.67945 0.3048)
			(end -0.67945 -0.305054)
			(stroke
				(width 0.1)
				(type default)
			)
			(layer "F.Fab")
		)
		(fp_line
			(start -0.67945 -0.305054)
			(end -0.12065 -0.305054)
			(stroke
				(width 0.1)
				(type default)
			)
			(layer "F.Fab")
		)
		(pad "1" smd circle
			(at -0.40005 0 180)
			(size 0 0)
			(layers "F.Cu" "F.Mask" "F.Paste")
			(net "P3V3_NIC5_CO_GATE")
		)
		(pad "2" smd circle
			(at 0.40005 0 180)
			(size 0 0)
			(layers "F.Cu" "F.Mask" "F.Paste")
			(net "GND")
		)
	)
)
